FILE_TYPE = CONNECTIVITY;
{Allegro Design Entry HDL 16.6-p007 (v16-6-112F) 10/10/2012}
"PAGE_NUMBER" = 110;
0"NC";
END.
